(kicad_pcb
	(version 20260206)
	(generator "pcbnew")
	(generator_version "10.0")
	(general
		(thickness 1.6)
		(legacy_teardrops no)
	)
	(paper "A4")
	(title_block
		(title "Bryce Canyon_R.DPB_16317-1_OCP.brd")
		(comment 1 "Bryce Canyon / footprints 361-367 of 2099")
	)
	(layers
		(0 "F.Cu" signal "TOP")
		(4 "In1.Cu" signal "L2GND")
		(6 "In2.Cu" signal "L3")
		(8 "In3.Cu" signal "L4VCC")
		(10 "In4.Cu" signal "L5VCC")
		(12 "In5.Cu" signal "L6")
		(14 "In6.Cu" signal "L7GND")
		(2 "B.Cu" signal "BOTTOM")
		(9 "F.Adhes" user "F.Adhesive")
		(11 "B.Adhes" user "B.Adhesive")
		(13 "F.Paste" user "Package Geometry/Pastemask Top")
		(15 "B.Paste" user "Package Geometry/Pastemask Bottom")
		(5 "F.SilkS" user "Ref Des/Silkscreen Top")
		(7 "B.SilkS" user "Ref Des/Silkscreen Bottom")
		(1 "F.Mask" user "Board Geometry/Soldermask Top")
		(3 "B.Mask" user "Board Geometry/Soldermask Bottom")
		(17 "Dwgs.User" user "User.Drawings")
		(19 "Cmts.User" user "User.Comments")
		(21 "Eco1.User" user "User.Eco1")
		(23 "Eco2.User" user "User.Eco2")
		(25 "Edge.Cuts" user "Board Geometry/Outline")
		(27 "Margin" user)
		(31 "F.CrtYd" user "Package Geometry/Place Bound Top")
		(29 "B.CrtYd" user "Package Geometry/Place Bound Bottom")
		(35 "F.Fab" user "Ref Des/Assembly Top")
		(33 "B.Fab" user "Ref Des/Assembly Bottom")
	)
	(footprint ""
		(layer "F.Cu")
		(at 35.687 -151.003 90)
		(property "Reference" "R353"
			(at 0 0 90)
			(layer "F.SilkS")
			(hide yes)
			(effects
				(font
					(size 1.27 1.27)
				)
			)
		)
		(property "Value" "220R3F-1-GP"
			(at -0.0254 -2.5146 90)
			(unlocked yes)
			(layer "F.Fab")
			(hide yes)
			(effects
				(font
					(size 1.016 1.016)
					(thickness 0.1524)
				)
			)
		)
		(property "Device Type" "R603H22"
			(at -0.0254 -4.0386 90)
			(unlocked yes)
			(layer "F.Fab")
			(hide yes)
			(effects
				(font
					(size 1.016 1.016)
					(thickness 0.1524)
				)
			)
		)
		(duplicate_pad_numbers_are_jumpers no)
		(fp_line
			(start 0.2032 0)
			(end 0.4826 0)
			(stroke
				(width 0.2032)
				(type default)
			)
			(layer "F.SilkS")
		)
		(fp_line
			(start -0.4826 0)
			(end -0.2032 0)
			(stroke
				(width 0.2032)
				(type default)
			)
			(layer "F.SilkS")
		)
		(fp_rect
			(start -0.5842 1.3335)
			(end 0.5842 -1.3335)
			(stroke
				(width 0)
				(type default)
			)
			(fill no)
			(layer "F.CrtYd")
		)
		(fp_rect
			(start -0.5842 1.3335)
			(end 0.5842 -1.3335)
			(stroke
				(width 0)
				(type default)
			)
			(fill no)
			(layer "F.Fab")
		)
		(pad "1" smd custom
			(at 0 -0.762 90)
			(size 0.2159 0.2159)
			(layers "F.Cu" "F.Mask" "F.Paste")
			(net "HDD_PRSNT_12")
			(options
				(clearance outline)
				(anchor circle)
			)
			(primitives
				(gr_poly
					(pts
						(arc
							(start -0.3302 -0.4318)
							(mid -0.402042 -0.402042)
							(end -0.4318 -0.3302)
						)
						(arc
							(start -0.4318 0.3302)
							(mid -0.402042 0.402042)
							(end -0.3302 0.4318)
						)
						(arc
							(start 0.3302 0.4318)
							(mid 0.402042 0.402042)
							(end 0.4318 0.3302)
						)
						(arc
							(start 0.4318 -0.3302)
							(mid 0.402042 -0.402042)
							(end 0.3302 -0.4318)
						)
					)
					(width 0)
					(fill yes)
				)
			)
		)
		(pad "2" smd custom
			(at 0 0.762 90)
			(size 0.2159 0.2159)
			(layers "F.Cu" "F.Mask" "F.Paste")
			(net "DRIVE_B_12_INS")
			(options
				(clearance outline)
				(anchor circle)
			)
			(primitives
				(gr_poly
					(pts
						(arc
							(start -0.3302 -0.4318)
							(mid -0.402042 -0.402042)
							(end -0.4318 -0.3302)
						)
						(arc
							(start -0.4318 0.3302)
							(mid -0.402042 0.402042)
							(end -0.3302 0.4318)
						)
						(arc
							(start 0.3302 0.4318)
							(mid 0.402042 0.402042)
							(end 0.4318 0.3302)
						)
						(arc
							(start 0.4318 -0.3302)
							(mid 0.402042 -0.402042)
							(end 0.3302 -0.4318)
						)
					)
					(width 0)
					(fill yes)
				)
			)
		)
	)
	(footprint ""
		(layer "F.Cu")
		(at 445.415924 -269.705074)
		(property "Reference" "TP71"
			(at 0 0 0)
			(layer "F.SilkS")
			(hide yes)
			(effects
				(font
					(size 1.27 1.27)
				)
			)
		)
		(property "Value" "*"
			(at -0.0508 -1.6764 0)
			(unlocked yes)
			(layer "F.Fab")
			(hide yes)
			(effects
				(font
					(size 1.016 1.016)
					(thickness 0.1524)
				)
			)
		)
		(property "Device Type" "TPAD32"
			(at -0.0508 -3.2004 0)
			(unlocked yes)
			(layer "F.Fab")
			(hide yes)
			(effects
				(font
					(size 1.016 1.016)
					(thickness 0.1524)
				)
			)
		)
		(duplicate_pad_numbers_are_jumpers no)
		(fp_poly
			(pts
				(arc
					(start 0.4064 0)
					(mid -0.4064 0)
					(end 0.4064 0)
				)
			)
			(stroke
				(width 0)
				(type default)
			)
			(fill no)
			(layer "F.CrtYd")
		)
		(fp_poly
			(pts
				(arc
					(start 0.7112 0)
					(mid -0.7112 0)
					(end 0.7112 0)
				)
			)
			(stroke
				(width 0)
				(type default)
			)
			(fill no)
			(layer "F.Fab")
		)
		(pad "1" smd circle
			(at 0 0)
			(size 0.8128 0.8128)
			(layers "F.Cu" "F.Mask" "F.Paste")
			(net "ACT_HDD_10")
		)
	)
	(footprint ""
		(layer "F.Cu")
		(at 168.529 -366.776 90)
		(property "Reference" "R984"
			(at 0 0 90)
			(layer "F.SilkS")
			(hide yes)
			(effects
				(font
					(size 1.27 1.27)
				)
			)
		)
		(property "Value" "10R2F-L-GP"
			(at 0.064008 -3.993896 90)
			(unlocked yes)
			(layer "F.Fab")
			(hide yes)
			(effects
				(font
					(size 1.016 1.016)
					(thickness 0.1524)
				)
			)
		)
		(property "Device Type" "R402H14"
			(at 0.064008 -5.517896 90)
			(unlocked yes)
			(layer "F.Fab")
			(hide yes)
			(effects
				(font
					(size 1.016 1.016)
					(thickness 0.1524)
				)
			)
		)
		(duplicate_pad_numbers_are_jumpers no)
		(fp_line
			(start 0.508 -0.9398)
			(end -0.508 -0.9398)
			(stroke
				(width 0.1524)
				(type default)
			)
			(layer "F.SilkS")
		)
		(fp_line
			(start -0.508 -0.9398)
			(end -0.508 0.9398)
			(stroke
				(width 0.1524)
				(type default)
			)
			(layer "F.SilkS")
		)
		(fp_rect
			(start -0.508 0.9398)
			(end 0.508 -0.9398)
			(stroke
				(width 0)
				(type default)
			)
			(fill no)
			(layer "F.CrtYd")
		)
		(fp_rect
			(start -0.508 0.9398)
			(end 0.508 -0.9398)
			(stroke
				(width 0)
				(type default)
			)
			(fill no)
			(layer "F.Fab")
		)
		(pad "1" smd custom
			(at 0 -0.4445 90)
			(size 0.1397 0.1397)
			(layers "F.Cu" "F.Mask" "F.Paste")
			(net "P12V_CLIP")
			(options
				(clearance outline)
				(anchor circle)
			)
			(primitives
				(gr_poly
					(pts
						(arc
							(start -0.1778 -0.2794)
							(mid -0.249642 -0.249642)
							(end -0.2794 -0.1778)
						)
						(arc
							(start -0.2794 0.1778)
							(mid -0.249642 0.249642)
							(end -0.1778 0.2794)
						)
						(arc
							(start 0.1778 0.2794)
							(mid 0.249642 0.249642)
							(end 0.2794 0.1778)
						)
						(arc
							(start 0.2794 -0.1778)
							(mid 0.249642 -0.249642)
							(end 0.1778 -0.2794)
						)
					)
					(width 0)
					(fill yes)
				)
			)
		)
		(pad "2" smd custom
			(at 0 0.4445 90)
			(size 0.1397 0.1397)
			(layers "F.Cu" "F.Mask" "F.Paste")
			(net "MB0_P12V_HS")
			(options
				(clearance outline)
				(anchor circle)
			)
			(primitives
				(gr_poly
					(pts
						(arc
							(start -0.1778 -0.2794)
							(mid -0.249642 -0.249642)
							(end -0.2794 -0.1778)
						)
						(arc
							(start -0.2794 0.1778)
							(mid -0.249642 0.249642)
							(end -0.1778 0.2794)
						)
						(arc
							(start 0.1778 0.2794)
							(mid 0.249642 0.249642)
							(end 0.2794 0.1778)
						)
						(arc
							(start 0.2794 -0.1778)
							(mid 0.249642 -0.249642)
							(end 0.1778 -0.2794)
						)
					)
					(width 0)
					(fill yes)
				)
			)
		)
	)
	(footprint ""
		(layer "F.Cu")
		(at 172.593 -145.796)
		(property "Reference" "Q78"
			(at 0 0 0)
			(layer "F.SilkS")
			(hide yes)
			(effects
				(font
					(size 1.27 1.27)
				)
			)
		)
		(property "Value" "AO4407AL-GP"
			(at -3.707384 -1.5367 0)
			(unlocked yes)
			(layer "F.Fab")
			(hide yes)
			(effects
				(font
					(size 1.016 1.016)
					(thickness 0.1524)
				)
			)
		)
		(property "Device Type" "SOIC8H69"
			(at -3.707384 -3.0607 0)
			(unlocked yes)
			(layer "F.Fab")
			(hide yes)
			(effects
				(font
					(size 1.016 1.016)
					(thickness 0.1524)
				)
			)
		)
		(duplicate_pad_numbers_are_jumpers no)
		(fp_line
			(start -2.7432 -1.4224)
			(end -2.7432 1.4224)
			(stroke
				(width 0.1524)
				(type default)
			)
			(layer "F.SilkS")
		)
		(fp_line
			(start -2.7432 1.4224)
			(end -2.6416 1.4224)
			(stroke
				(width 0.1524)
				(type default)
			)
			(layer "F.SilkS")
		)
		(fp_line
			(start -2.7432 1.4224)
			(end 2.1336 1.4224)
			(stroke
				(width 0.1524)
				(type default)
			)
			(layer "F.SilkS")
		)
		(fp_line
			(start -2.7178 -0.508)
			(end -2.1844 -0.0508)
			(stroke
				(width 0.1524)
				(type default)
			)
			(layer "F.SilkS")
		)
		(fp_line
			(start -2.6289 3.4417)
			(end -2.6289 1.4732)
			(stroke
				(width 0.381)
				(type default)
			)
			(layer "F.SilkS")
		)
		(fp_line
			(start -2.1844 -0.0508)
			(end -2.7178 0.508)
			(stroke
				(width 0.1524)
				(type default)
			)
			(layer "F.SilkS")
		)
		(fp_line
			(start 2.1336 -1.4224)
			(end -2.7432 -1.4224)
			(stroke
				(width 0.1524)
				(type default)
			)
			(layer "F.SilkS")
		)
		(fp_line
			(start 2.1336 1.4224)
			(end 2.1336 -1.4224)
			(stroke
				(width 0.1524)
				(type default)
			)
			(layer "F.SilkS")
		)
		(fp_poly
			(pts
				(xy -2.2098 -1.4224) (xy -2.2098 1.4224) (xy 2.2098 1.4224) (xy 2.2098 -1.4224)
			)
			(stroke
				(width 0)
				(type default)
			)
			(fill yes)
			(layer "F.SilkS")
		)
		(fp_rect
			(start -2.450084 2.999994)
			(end 2.450084 -2.999994)
			(stroke
				(width 0)
				(type default)
			)
			(fill no)
			(layer "F.CrtYd")
		)
		(fp_poly
			(pts
				(xy -2.8194 3.6322) (xy -2.8194 -3.6322) (xy 2.8194 -3.6322) (xy 2.8194 1.18364) (xy 2.450084 1.18364)
				(xy 2.450084 -2.999994) (xy -2.450084 -2.999994) (xy -2.450084 2.999994) (xy 2.450084 2.999994)
				(xy 2.450084 1.18618) (xy 2.8194 1.18618) (xy 2.8194 3.6322)
			)
			(stroke
				(width 0)
				(type default)
			)
			(fill no)
			(layer "F.CrtYd")
		)
		(fp_rect
			(start -2.8194 3.6322)
			(end 2.8194 -3.6322)
			(stroke
				(width 0)
				(type default)
			)
			(fill no)
			(layer "F.Fab")
		)
		(pad "1" smd rect
			(at -1.905 2.54)
			(size 0.635 1.651)
			(layers "F.Cu" "F.Mask" "F.Paste")
			(net "P12V_B")
		)
		(pad "2" smd rect
			(at -0.635 2.54)
			(size 0.635 1.651)
			(layers "F.Cu" "F.Mask" "F.Paste")
			(net "P12V_B")
		)
		(pad "3" smd rect
			(at 0.635 2.54)
			(size 0.635 1.651)
			(layers "F.Cu" "F.Mask" "F.Paste")
			(net "P12V_B")
		)
		(pad "4" smd rect
			(at 1.905 2.54)
			(size 0.635 1.651)
			(layers "F.Cu" "F.Mask" "F.Paste")
			(net "SW_HDD_N17")
		)
		(pad "5" smd rect
			(at 1.905 -2.54)
			(size 0.635 1.651)
			(layers "F.Cu" "F.Mask" "F.Paste")
			(net "P12V_HDD17")
		)
		(pad "6" smd rect
			(at 0.635 -2.54)
			(size 0.635 1.651)
			(layers "F.Cu" "F.Mask" "F.Paste")
			(net "P12V_HDD17")
		)
		(pad "7" smd rect
			(at -0.635 -2.54)
			(size 0.635 1.651)
			(layers "F.Cu" "F.Mask" "F.Paste")
			(net "P12V_HDD17")
		)
		(pad "8" smd rect
			(at -1.905 -2.54)
			(size 0.635 1.651)
			(layers "F.Cu" "F.Mask" "F.Paste")
			(net "P12V_HDD17")
		)
	)
	(footprint ""
		(layer "F.Cu")
		(at 462.915 -148.082)
		(property "Reference" "Q108"
			(at 0 0 0)
			(layer "F.SilkS")
			(hide yes)
			(effects
				(font
					(size 1.27 1.27)
				)
			)
		)
		(property "Value" "AO4407AL-GP"
			(at -3.707384 -1.5367 0)
			(unlocked yes)
			(layer "F.Fab")
			(hide yes)
			(effects
				(font
					(size 1.016 1.016)
					(thickness 0.1524)
				)
			)
		)
		(property "Device Type" "SOIC8H69"
			(at -3.707384 -3.0607 0)
			(unlocked yes)
			(layer "F.Fab")
			(hide yes)
			(effects
				(font
					(size 1.016 1.016)
					(thickness 0.1524)
				)
			)
		)
		(duplicate_pad_numbers_are_jumpers no)
		(fp_line
			(start -2.7432 -1.4224)
			(end -2.7432 1.4224)
			(stroke
				(width 0.1524)
				(type default)
			)
			(layer "F.SilkS")
		)
		(fp_line
			(start -2.7432 1.4224)
			(end -2.6416 1.4224)
			(stroke
				(width 0.1524)
				(type default)
			)
			(layer "F.SilkS")
		)
		(fp_line
			(start -2.7432 1.4224)
			(end 2.1336 1.4224)
			(stroke
				(width 0.1524)
				(type default)
			)
			(layer "F.SilkS")
		)
		(fp_line
			(start -2.7178 -0.508)
			(end -2.1844 -0.0508)
			(stroke
				(width 0.1524)
				(type default)
			)
			(layer "F.SilkS")
		)
		(fp_line
			(start -2.6289 3.4417)
			(end -2.6289 1.4732)
			(stroke
				(width 0.381)
				(type default)
			)
			(layer "F.SilkS")
		)
		(fp_line
			(start -2.1844 -0.0508)
			(end -2.7178 0.508)
			(stroke
				(width 0.1524)
				(type default)
			)
			(layer "F.SilkS")
		)
		(fp_line
			(start 2.1336 -1.4224)
			(end -2.7432 -1.4224)
			(stroke
				(width 0.1524)
				(type default)
			)
			(layer "F.SilkS")
		)
		(fp_line
			(start 2.1336 1.4224)
			(end 2.1336 -1.4224)
			(stroke
				(width 0.1524)
				(type default)
			)
			(layer "F.SilkS")
		)
		(fp_poly
			(pts
				(xy -2.2098 -1.4224) (xy -2.2098 1.4224) (xy 2.2098 1.4224) (xy 2.2098 -1.4224)
			)
			(stroke
				(width 0)
				(type default)
			)
			(fill yes)
			(layer "F.SilkS")
		)
		(fp_rect
			(start -2.450084 2.999994)
			(end 2.450084 -2.999994)
			(stroke
				(width 0)
				(type default)
			)
			(fill no)
			(layer "F.CrtYd")
		)
		(fp_poly
			(pts
				(xy -2.8194 3.6322) (xy -2.8194 -3.6322) (xy 2.8194 -3.6322) (xy 2.8194 1.18364) (xy 2.450084 1.18364)
				(xy 2.450084 -2.999994) (xy -2.450084 -2.999994) (xy -2.450084 2.999994) (xy 2.450084 2.999994)
				(xy 2.450084 1.18618) (xy 2.8194 1.18618) (xy 2.8194 3.6322)
			)
			(stroke
				(width 0)
				(type default)
			)
			(fill no)
			(layer "F.CrtYd")
		)
		(fp_rect
			(start -2.8194 3.6322)
			(end 2.8194 -3.6322)
			(stroke
				(width 0)
				(type default)
			)
			(fill no)
			(layer "F.Fab")
		)
		(pad "1" smd rect
			(at -1.905 2.54)
			(size 0.635 1.651)
			(layers "F.Cu" "F.Mask" "F.Paste")
			(net "P12V_B")
		)
		(pad "2" smd rect
			(at -0.635 2.54)
			(size 0.635 1.651)
			(layers "F.Cu" "F.Mask" "F.Paste")
			(net "P12V_B")
		)
		(pad "3" smd rect
			(at 0.635 2.54)
			(size 0.635 1.651)
			(layers "F.Cu" "F.Mask" "F.Paste")
			(net "P12V_B")
		)
		(pad "4" smd rect
			(at 1.905 2.54)
			(size 0.635 1.651)
			(layers "F.Cu" "F.Mask" "F.Paste")
			(net "SW_HDD_N22")
		)
		(pad "5" smd rect
			(at 1.905 -2.54)
			(size 0.635 1.651)
			(layers "F.Cu" "F.Mask" "F.Paste")
			(net "P12V_HDD22")
		)
		(pad "6" smd rect
			(at 0.635 -2.54)
			(size 0.635 1.651)
			(layers "F.Cu" "F.Mask" "F.Paste")
			(net "P12V_HDD22")
		)
		(pad "7" smd rect
			(at -0.635 -2.54)
			(size 0.635 1.651)
			(layers "F.Cu" "F.Mask" "F.Paste")
			(net "P12V_HDD22")
		)
		(pad "8" smd rect
			(at -1.905 -2.54)
			(size 0.635 1.651)
			(layers "F.Cu" "F.Mask" "F.Paste")
			(net "P12V_HDD22")
		)
	)
	(footprint ""
		(layer "F.Cu")
		(at 464.82 -143.891 90)
		(property "Reference" "C325"
			(at 0 0 90)
			(layer "F.SilkS")
			(hide yes)
			(effects
				(font
					(size 1.27 1.27)
				)
			)
		)
		(property "Value" "SCD033U25V2KX-GP"
			(at 1.1811 -2.7051 90)
			(unlocked yes)
			(layer "F.Fab")
			(hide yes)
			(effects
				(font
					(size 1.016 1.016)
					(thickness 0.1524)
				)
			)
		)
		(property "Device Type" "C402H22"
			(at 1.1811 -4.2291 90)
			(unlocked yes)
			(layer "F.Fab")
			(hide yes)
			(effects
				(font
					(size 1.016 1.016)
					(thickness 0.1524)
				)
			)
		)
		(duplicate_pad_numbers_are_jumpers no)
		(fp_rect
			(start -0.4318 0.9525)
			(end 0.4318 -0.9525)
			(stroke
				(width 0)
				(type default)
			)
			(fill no)
			(layer "F.CrtYd")
		)
		(fp_rect
			(start -0.4318 0.9525)
			(end 0.4318 -0.9525)
			(stroke
				(width 0)
				(type default)
			)
			(fill no)
			(layer "F.Fab")
		)
		(pad "1" smd custom
			(at 0 -0.4445 90)
			(size 0.1524 0.1524)
			(layers "F.Cu" "F.Mask" "F.Paste")
			(net "P12V_B")
			(options
				(clearance outline)
				(anchor circle)
			)
			(primitives
				(gr_poly
					(pts
						(arc
							(start 0.3048 -0.2032)
							(mid 0.275042 -0.275042)
							(end 0.2032 -0.3048)
						)
						(arc
							(start -0.2032 -0.3048)
							(mid -0.275042 -0.275042)
							(end -0.3048 -0.2032)
						)
						(arc
							(start -0.3048 0.2032)
							(mid -0.275042 0.275042)
							(end -0.2032 0.3048)
						)
						(arc
							(start 0.2032 0.3048)
							(mid 0.275042 0.275042)
							(end 0.3048 0.2032)
						)
					)
					(width 0)
					(fill yes)
				)
			)
		)
		(pad "2" smd custom
			(at 0 0.4445 90)
			(size 0.1524 0.1524)
			(layers "F.Cu" "F.Mask" "F.Paste")
			(net "SW_HDD_N22")
			(options
				(clearance outline)
				(anchor circle)
			)
			(primitives
				(gr_poly
					(pts
						(arc
							(start 0.3048 -0.2032)
							(mid 0.275042 -0.275042)
							(end 0.2032 -0.3048)
						)
						(arc
							(start -0.2032 -0.3048)
							(mid -0.275042 -0.275042)
							(end -0.3048 -0.2032)
						)
						(arc
							(start -0.3048 0.2032)
							(mid -0.275042 0.275042)
							(end -0.2032 0.3048)
						)
						(arc
							(start 0.2032 0.3048)
							(mid 0.275042 0.275042)
							(end 0.3048 0.2032)
						)
					)
					(width 0)
					(fill yes)
				)
			)
		)
	)
	(footprint ""
		(layer "F.Cu")
		(at 118.872 -160.401 180)
		(property "Reference" "C231"
			(at 0 0 180)
			(layer "F.SilkS")
			(hide yes)
			(effects
				(font
					(size 1.27 1.27)
				)
			)
		)
		(property "Value" "SC1U25V3KX-GP"
			(at 0 -2.8194 180)
			(unlocked yes)
			(layer "F.Fab")
			(hide yes)
			(effects
				(font
					(size 1.016 1.016)
					(thickness 0.1524)
				)
			)
		)
		(property "Device Type" "C603H36"
			(at 0 -4.3434 180)
			(unlocked yes)
			(layer "F.Fab")
			(hide yes)
			(effects
				(font
					(size 1.016 1.016)
					(thickness 0.1524)
				)
			)
		)
		(duplicate_pad_numbers_are_jumpers no)
		(fp_line
			(start 0.508 0)
			(end -0.508 0)
			(stroke
				(width 0.2032)
				(type default)
			)
			(layer "F.SilkS")
		)
		(fp_rect
			(start -0.5842 1.3335)
			(end 0.5842 -1.3335)
			(stroke
				(width 0)
				(type default)
			)
			(fill no)
			(layer "F.CrtYd")
		)
		(fp_rect
			(start -0.5842 1.3335)
			(end 0.5842 -1.3335)
			(stroke
				(width 0)
				(type default)
			)
			(fill no)
			(layer "F.Fab")
		)
		(pad "1" smd custom
			(at 0 -0.762 180)
			(size 0.2159 0.2159)
			(layers "F.Cu" "F.Mask" "F.Paste")
			(net "P12V_HDD15")
			(options
				(clearance outline)
				(anchor circle)
			)
			(primitives
				(gr_poly
					(pts
						(arc
							(start -0.3302 -0.4318)
							(mid -0.402042 -0.402042)
							(end -0.4318 -0.3302)
						)
						(arc
							(start -0.4318 0.3302)
							(mid -0.402042 0.402042)
							(end -0.3302 0.4318)
						)
						(arc
							(start 0.3302 0.4318)
							(mid 0.402042 0.402042)
							(end 0.4318 0.3302)
						)
						(arc
							(start 0.4318 -0.3302)
							(mid 0.402042 -0.402042)
							(end 0.3302 -0.4318)
						)
					)
					(width 0)
					(fill yes)
				)
			)
		)
		(pad "2" smd custom
			(at 0 0.762 180)
			(size 0.2159 0.2159)
			(layers "F.Cu" "F.Mask" "F.Paste")
			(net "GND")
			(options
				(clearance outline)
				(anchor circle)
			)
			(primitives
				(gr_poly
					(pts
						(arc
							(start -0.3302 -0.4318)
							(mid -0.402042 -0.402042)
							(end -0.4318 -0.3302)
						)
						(arc
							(start -0.4318 0.3302)
							(mid -0.402042 0.402042)
							(end -0.3302 0.4318)
						)
						(arc
							(start 0.3302 0.4318)
							(mid 0.402042 0.402042)
							(end 0.4318 0.3302)
						)
						(arc
							(start 0.4318 -0.3302)
							(mid 0.402042 -0.402042)
							(end 0.3302 -0.4318)
						)
					)
					(width 0)
					(fill yes)
				)
			)
		)
	)
)
